# BASEBOARD_FAB2 (Tioga Pass) — schematic netlist excerpt (pin names and nets, part order shuffled) for the footprints in the layout excerpt that follows; sources: Cadence DE-HDL packaged netlist, KiCad conversion of Wiwynn_Tioga_Pass_MB.brd

R2T69  RES  0.0 5% EMPTY  pkg 0402  page 93 : A = H_CPU1_PROCHOT_G_N ; B = H_CPU1_PROCHOT_G_PCH_N
R2L17  RES  0.0 5% CHIP  pkg 0402  page 235 : A = PWRGD_P1V8_PCH_STBY ; B = VR_PVNN_PCH_VREN
R6W12  RES  4.75K 1% CHIP  pkg 0402  page 247 : A = SMB_DEBUG_STBY_LVC3_SDA ; B = P3V3_STBY

(kicad_pcb
	(version 20260206)
	(generator "pcbnew")
	(generator_version "10.0")
	(general
		(thickness 1.6)
		(legacy_teardrops no)
	)
	(paper "A4")
	(title_block
		(title "Wiwynn_Tioga_Pass_MB.brd")
		(comment 1 "Tioga Pass / footprints 3733-3735 of 4770")
	)
	(layers
		(0 "F.Cu" signal "TOP")
		(4 "In1.Cu" signal "L2GND")
		(6 "In2.Cu" signal "L3")
		(8 "In3.Cu" signal "L4GND")
		(10 "In4.Cu" signal "L5")
		(12 "In5.Cu" signal "L6GND")
		(14 "In6.Cu" signal "L7VCC")
		(16 "In7.Cu" signal "L8VCC")
		(18 "In8.Cu" signal "L9GND")
		(20 "In9.Cu" signal "L10")
		(22 "In10.Cu" signal "L11GND")
		(24 "In11.Cu" signal "L12")
		(26 "In12.Cu" signal "L13GND")
		(2 "B.Cu" signal "BOTTOM")
		(9 "F.Adhes" user "F.Adhesive")
		(11 "B.Adhes" user "B.Adhesive")
		(13 "F.Paste" user "Package Geometry/Pastemask Top")
		(15 "B.Paste" user "Package Geometry/Pastemask Bottom")
		(5 "F.SilkS" user "Ref Des/Silkscreen Top")
		(7 "B.SilkS" user "Ref Des/Silkscreen Bottom")
		(1 "F.Mask" user "Board Geometry/Soldermask Top")
		(3 "B.Mask" user "Board Geometry/Soldermask Bottom")
		(17 "Dwgs.User" user "User.Drawings")
		(19 "Cmts.User" user "User.Comments")
		(21 "Eco1.User" user "User.Eco1")
		(23 "Eco2.User" user "User.Eco2")
		(25 "Edge.Cuts" user "Board Geometry/Outline")
		(27 "Margin" user)
		(31 "F.CrtYd" user "Package Geometry/Place Bound Top")
		(29 "B.CrtYd" user "Package Geometry/Place Bound Bottom")
		(35 "F.Fab" user "Ref Des/Assembly Top")
		(33 "B.Fab" user "Ref Des/Assembly Bottom")
	)
	(footprint ""
		(layer "B.Cu")
		(at 400.829526 -149.663912 -90)
		(property "Reference" "R2L17"
			(at 0.8382 -0.84963 270)
			(unlocked yes)
			(layer "B.SilkS")
			(effects
				(font
					(size 0.7874 0.5842)
					(thickness 0.1524)
				)
				(justify left mirror)
			)
		)
		(property "Value" ""
			(at 0 0 90)
			(layer "B.Fab")
			(effects
				(font
					(size 1.27 1.27)
				)
				(justify mirror)
			)
		)
		(duplicate_pad_numbers_are_jumpers no)
		(fp_poly
			(pts
				(xy 0.2794 -0.1016) (xy -0.2794 -0.1016) (xy -0.2794 0.9906) (xy 0.2794 0.9906)
			)
			(stroke
				(width 0)
				(type default)
			)
			(fill no)
			(layer "B.CrtYd")
		)
		(fp_line
			(start -0.2794 0.9906)
			(end -0.2794 -0.1016)
			(stroke
				(width 0.1)
				(type default)
			)
			(layer "B.Fab")
		)
		(fp_line
			(start 0.2794 0.9906)
			(end -0.2794 0.9906)
			(stroke
				(width 0.1)
				(type default)
			)
			(layer "B.Fab")
		)
		(fp_line
			(start -0.2794 -0.1016)
			(end 0.2794 -0.1016)
			(stroke
				(width 0.1)
				(type default)
			)
			(layer "B.Fab")
		)
		(fp_line
			(start 0.2794 -0.1016)
			(end 0.2794 0.9906)
			(stroke
				(width 0.1)
				(type default)
			)
			(layer "B.Fab")
		)
		(pad "1" smd rect
			(at 0 0 90)
			(size 0.508 0.508)
			(layers "B.Cu" "B.Mask" "B.Paste")
			(net "PWRGD_P1V8_PCH_STBY")
		)
		(pad "2" smd rect
			(at 0 0.889 90)
			(size 0.508 0.508)
			(layers "B.Cu" "B.Mask" "B.Paste")
			(net "VR_PVNN_PCH_VREN")
		)
		(zone
			(layer "B.Cu")
			(hatch none 0.5)
			(connect_pads
				(clearance 0)
			)
			(min_thickness 0.25)
			(keepout
				(tracks not_allowed)
				(vias allowed)
				(pads allowed)
				(copperpour not_allowed)
				(footprints allowed)
			)
			(placement
				(enabled no)
				(sheetname "")
			)
			(fill
				(thermal_gap 0.5)
				(thermal_bridge_width 0.5)
				(island_removal_mode 0)
			)
			(polygon
				(pts
					(xy 400.194526 -149.409912) (xy 400.194526 -149.917912) (xy 400.575526 -149.917912) (xy 400.575526 -149.409912)
				)
			)
		)
		(zone
			(layer "B.Cu")
			(hatch none 0.5)
			(connect_pads
				(clearance 0)
			)
			(min_thickness 0.25)
			(keepout
				(tracks allowed)
				(vias not_allowed)
				(pads allowed)
				(copperpour not_allowed)
				(footprints allowed)
			)
			(placement
				(enabled no)
				(sheetname "")
			)
			(fill
				(thermal_gap 0.5)
				(thermal_bridge_width 0.5)
				(island_removal_mode 0)
			)
			(polygon
				(pts
					(xy 400.575526 -149.409912) (xy 400.575526 -149.917912) (xy 400.194526 -149.917912) (xy 400.194526 -149.409912)
				)
			)
		)
	)
	(footprint ""
		(layer "B.Cu")
		(at 474.650816 -145.470372 180)
		(property "Reference" "R6W12"
			(at 0.8382 -0.67818 180)
			(unlocked yes)
			(layer "B.SilkS")
			(effects
				(font
					(size 0.4064 0.254)
					(thickness 0.1524)
				)
				(justify left mirror)
			)
		)
		(property "Value" ""
			(at 0 0 0)
			(layer "B.Fab")
			(effects
				(font
					(size 1.27 1.27)
				)
				(justify mirror)
			)
		)
		(duplicate_pad_numbers_are_jumpers no)
		(fp_poly
			(pts
				(xy 0.2794 -0.1016) (xy -0.2794 -0.1016) (xy -0.2794 0.9906) (xy 0.2794 0.9906)
			)
			(stroke
				(width 0)
				(type default)
			)
			(fill no)
			(layer "B.CrtYd")
		)
		(fp_line
			(start 0.2794 0.9906)
			(end -0.2794 0.9906)
			(stroke
				(width 0.1)
				(type default)
			)
			(layer "B.Fab")
		)
		(fp_line
			(start 0.2794 -0.1016)
			(end 0.2794 0.9906)
			(stroke
				(width 0.1)
				(type default)
			)
			(layer "B.Fab")
		)
		(fp_line
			(start -0.2794 0.9906)
			(end -0.2794 -0.1016)
			(stroke
				(width 0.1)
				(type default)
			)
			(layer "B.Fab")
		)
		(fp_line
			(start -0.2794 -0.1016)
			(end 0.2794 -0.1016)
			(stroke
				(width 0.1)
				(type default)
			)
			(layer "B.Fab")
		)
		(pad "1" smd rect
			(at 0 0)
			(size 0.508 0.508)
			(layers "B.Cu" "B.Mask" "B.Paste")
			(net "SMB_DEBUG_STBY_LVC3_SDA")
		)
		(pad "2" smd rect
			(at 0 0.889)
			(size 0.508 0.508)
			(layers "B.Cu" "B.Mask" "B.Paste")
			(net "P3V3_STBY")
		)
		(zone
			(layer "B.Cu")
			(hatch none 0.5)
			(connect_pads
				(clearance 0)
			)
			(min_thickness 0.25)
			(keepout
				(tracks not_allowed)
				(vias allowed)
				(pads allowed)
				(copperpour not_allowed)
				(footprints allowed)
			)
			(placement
				(enabled no)
				(sheetname "")
			)
			(fill
				(thermal_gap 0.5)
				(thermal_bridge_width 0.5)
				(island_removal_mode 0)
			)
			(polygon
				(pts
					(xy 474.396816 -146.105372) (xy 474.904816 -146.105372) (xy 474.904816 -145.724372) (xy 474.396816 -145.724372)
				)
			)
		)
		(zone
			(layer "B.Cu")
			(hatch none 0.5)
			(connect_pads
				(clearance 0)
			)
			(min_thickness 0.25)
			(keepout
				(tracks allowed)
				(vias not_allowed)
				(pads allowed)
				(copperpour not_allowed)
				(footprints allowed)
			)
			(placement
				(enabled no)
				(sheetname "")
			)
			(fill
				(thermal_gap 0.5)
				(thermal_bridge_width 0.5)
				(island_removal_mode 0)
			)
			(polygon
				(pts
					(xy 474.396816 -145.724372) (xy 474.904816 -145.724372) (xy 474.904816 -146.105372) (xy 474.396816 -146.105372)
				)
			)
		)
	)
	(footprint ""
		(layer "B.Cu")
		(at 371.362986 -47.798482 180)
		(property "Reference" "R2T69"
			(at 0 0 0)
			(layer "B.SilkS")
			(hide yes)
			(effects
				(font
					(size 1.27 1.27)
				)
				(justify mirror)
			)
		)
		(property "Value" ""
			(at 0 0 0)
			(layer "B.Fab")
			(effects
				(font
					(size 1.27 1.27)
				)
				(justify mirror)
			)
		)
		(duplicate_pad_numbers_are_jumpers no)
		(fp_poly
			(pts
				(xy 0.2794 -0.1016) (xy -0.2794 -0.1016) (xy -0.2794 0.9906) (xy 0.2794 0.9906)
			)
			(stroke
				(width 0)
				(type default)
			)
			(fill no)
			(layer "B.CrtYd")
		)
		(fp_line
			(start 0.2794 0.9906)
			(end -0.2794 0.9906)
			(stroke
				(width 0.1)
				(type default)
			)
			(layer "B.Fab")
		)
		(fp_line
			(start 0.2794 -0.1016)
			(end 0.2794 0.9906)
			(stroke
				(width 0.1)
				(type default)
			)
			(layer "B.Fab")
		)
		(fp_line
			(start -0.2794 0.9906)
			(end -0.2794 -0.1016)
			(stroke
				(width 0.1)
				(type default)
			)
			(layer "B.Fab")
		)
		(fp_line
			(start -0.2794 -0.1016)
			(end 0.2794 -0.1016)
			(stroke
				(width 0.1)
				(type default)
			)
			(layer "B.Fab")
		)
		(pad "1" smd rect
			(at 0 0)
			(size 0.508 0.508)
			(layers "B.Cu" "B.Mask" "B.Paste")
			(net "H_CPU1_PROCHOT_G_N")
		)
		(pad "2" smd rect
			(at 0 0.889)
			(size 0.508 0.508)
			(layers "B.Cu" "B.Mask" "B.Paste")
			(net "H_CPU1_PROCHOT_G_PCH_N")
		)
		(zone
			(layer "B.Cu")
			(hatch none 0.5)
			(connect_pads
				(clearance 0)
			)
			(min_thickness 0.25)
			(keepout
				(tracks not_allowed)
				(vias allowed)
				(pads allowed)
				(copperpour not_allowed)
				(footprints allowed)
			)
			(placement
				(enabled no)
				(sheetname "")
			)
			(fill
				(thermal_gap 0.5)
				(thermal_bridge_width 0.5)
				(island_removal_mode 0)
			)
			(polygon
				(pts
					(xy 371.108986 -48.433482) (xy 371.616986 -48.433482) (xy 371.616986 -48.052482) (xy 371.108986 -48.052482)
				)
			)
		)
		(zone
			(layer "B.Cu")
			(hatch none 0.5)
			(connect_pads
				(clearance 0)
			)
			(min_thickness 0.25)
			(keepout
				(tracks allowed)
				(vias not_allowed)
				(pads allowed)
				(copperpour not_allowed)
				(footprints allowed)
			)
			(placement
				(enabled no)
				(sheetname "")
			)
			(fill
				(thermal_gap 0.5)
				(thermal_bridge_width 0.5)
				(island_removal_mode 0)
			)
			(polygon
				(pts
					(xy 371.108986 -48.052482) (xy 371.616986 -48.052482) (xy 371.616986 -48.433482) (xy 371.108986 -48.433482)
				)
			)
		)
	)
)
